# S9S_MB_2U (Grand Teton) — schematic netlist excerpt (pin names and nets, part order shuffled) for the footprints in the layout excerpt that follows; sources: Cadence DE-HDL packaged netlist, KiCad conversion of 03242023_DA0F0TMBIJ0_F0T_Motherboard_J_brd_V01_OCP.brd

R2132  Q_RES  0 5% EMPTY  pkg 0402LF  page 202 : A = JTAG_TRC_PCH_PTI<6> ; B = FM_ESPI_PLD_R1_EN
R2253  Q_RES  4.75K 1% CHIP  pkg 0402LF  page 197 : A = P3V3_AUX ; B = PECI_MUX_SEL_R

(kicad_pcb
	(version 20260206)
	(generator "pcbnew")
	(generator_version "10.0")
	(general
		(thickness 1.6)
		(legacy_teardrops no)
	)
	(paper "A4")
	(title_block
		(title "03242023_DA0F0TMBIJ0_F0T_Motherboard_J_brd_V01_OCP.brd")
		(comment 1 "Grand Teton / footprints 2736-2737 of 6105")
	)
	(layers
		(0 "F.Cu" signal "TOP")
		(4 "In1.Cu" signal "GND")
		(6 "In2.Cu" signal "IN1")
		(8 "In3.Cu" signal "GND1")
		(10 "In4.Cu" signal "IN2")
		(12 "In5.Cu" signal "GND2")
		(14 "In6.Cu" signal "IN3")
		(16 "In7.Cu" signal "GND3")
		(18 "In8.Cu" signal "VCC")
		(20 "In9.Cu" signal "VCC1")
		(22 "In10.Cu" signal "GND4")
		(24 "In11.Cu" signal "IN4")
		(26 "In12.Cu" signal "GND5")
		(28 "In13.Cu" signal "IN5")
		(30 "In14.Cu" signal "GND6")
		(32 "In15.Cu" signal "IN6")
		(34 "In16.Cu" signal "GND7")
		(2 "B.Cu" signal "BOTTOM")
		(9 "F.Adhes" user "F.Adhesive")
		(11 "B.Adhes" user "B.Adhesive")
		(13 "F.Paste" user "Package Geometry/Pastemask Top")
		(15 "B.Paste" user "Package Geometry/Pastemask Bottom")
		(5 "F.SilkS" user "Ref Des/Silkscreen Top")
		(7 "B.SilkS" user "Ref Des/Silkscreen Bottom")
		(1 "F.Mask" user "Board Geometry/Soldermask Top")
		(3 "B.Mask" user "Board Geometry/Soldermask Bottom")
		(17 "Dwgs.User" user "User.Drawings")
		(19 "Cmts.User" user "User.Comments")
		(21 "Eco1.User" user "User.Eco1")
		(23 "Eco2.User" user "User.Eco2")
		(25 "Edge.Cuts" user "Board Geometry/Outline")
		(27 "Margin" user)
		(31 "F.CrtYd" user "Package Geometry/Place Bound Top")
		(29 "B.CrtYd" user "Package Geometry/Place Bound Bottom")
		(35 "F.Fab" user "Ref Des/Assembly Top")
		(33 "B.Fab" user "Ref Des/Assembly Bottom")
	)
	(footprint ""
		(layer "F.Cu")
		(at 332.68666 -16.2052 -90)
		(property "Reference" "R2132"
			(at 0 0 270)
			(layer "F.SilkS")
			(hide yes)
			(effects
				(font
					(size 1.27 1.27)
				)
			)
		)
		(property "Value" ""
			(at 0 0 270)
			(layer "F.Fab")
			(effects
				(font
					(size 1.27 1.27)
				)
			)
		)
		(duplicate_pad_numbers_are_jumpers no)
		(fp_line
			(start -0.7874 0.4064)
			(end -0.7874 -0.4064)
			(stroke
				(width 0.1524)
				(type default)
			)
			(layer "F.SilkS")
		)
		(fp_line
			(start 0.7874 0.4064)
			(end -0.7874 0.4064)
			(stroke
				(width 0.1524)
				(type default)
			)
			(layer "F.SilkS")
		)
		(fp_line
			(start -0.7874 -0.4064)
			(end 0.7874 -0.4064)
			(stroke
				(width 0.1524)
				(type default)
			)
			(layer "F.SilkS")
		)
		(fp_line
			(start 0.7874 -0.4064)
			(end 0.7874 0.4064)
			(stroke
				(width 0.1524)
				(type default)
			)
			(layer "F.SilkS")
		)
		(fp_line
			(start -0.67945 0.3048)
			(end -0.67945 -0.305054)
			(stroke
				(width 0.1)
				(type default)
			)
			(layer "F.Fab")
		)
		(fp_line
			(start -0.12065 0.3048)
			(end -0.67945 0.3048)
			(stroke
				(width 0.1)
				(type default)
			)
			(layer "F.Fab")
		)
		(fp_line
			(start 0.120396 0.3048)
			(end 0.120396 0.2794)
			(stroke
				(width 0.1)
				(type default)
			)
			(layer "F.Fab")
		)
		(fp_line
			(start 0.67945 0.3048)
			(end 0.120396 0.3048)
			(stroke
				(width 0.1)
				(type default)
			)
			(layer "F.Fab")
		)
		(fp_line
			(start -0.12065 0.2794)
			(end -0.12065 0.3048)
			(stroke
				(width 0.1)
				(type default)
			)
			(layer "F.Fab")
		)
		(fp_line
			(start 0.120396 0.2794)
			(end -0.12065 0.2794)
			(stroke
				(width 0.1)
				(type default)
			)
			(layer "F.Fab")
		)
		(fp_line
			(start -0.12065 -0.2794)
			(end 0.12065 -0.2794)
			(stroke
				(width 0.1)
				(type default)
			)
			(layer "F.Fab")
		)
		(fp_line
			(start 0.12065 -0.2794)
			(end 0.12065 -0.3048)
			(stroke
				(width 0.1)
				(type default)
			)
			(layer "F.Fab")
		)
		(fp_line
			(start 0.12065 -0.3048)
			(end 0.67945 -0.3048)
			(stroke
				(width 0.1)
				(type default)
			)
			(layer "F.Fab")
		)
		(fp_line
			(start 0.67945 -0.3048)
			(end 0.67945 0.3048)
			(stroke
				(width 0.1)
				(type default)
			)
			(layer "F.Fab")
		)
		(fp_line
			(start -0.67945 -0.305054)
			(end -0.12065 -0.305054)
			(stroke
				(width 0.1)
				(type default)
			)
			(layer "F.Fab")
		)
		(fp_line
			(start -0.12065 -0.305054)
			(end -0.12065 -0.2794)
			(stroke
				(width 0.1)
				(type default)
			)
			(layer "F.Fab")
		)
		(pad "1" smd circle
			(at -0.40005 0 270)
			(size 0 0)
			(layers "F.Cu" "F.Mask" "F.Paste")
			(net "JTAG_TRC_PCH_PTI<6>")
		)
		(pad "2" smd circle
			(at 0.40005 0 270)
			(size 0 0)
			(layers "F.Cu" "F.Mask" "F.Paste")
			(net "FM_ESPI_PLD_R1_EN")
		)
	)
	(footprint ""
		(layer "F.Cu")
		(at 304.53965 -60.094368)
		(property "Reference" "R2253"
			(at 0 0 0)
			(layer "F.SilkS")
			(hide yes)
			(effects
				(font
					(size 1.27 1.27)
				)
			)
		)
		(property "Value" ""
			(at 0 0 0)
			(layer "F.Fab")
			(effects
				(font
					(size 1.27 1.27)
				)
			)
		)
		(duplicate_pad_numbers_are_jumpers no)
		(fp_line
			(start -0.7874 -0.4064)
			(end 0.7874 -0.4064)
			(stroke
				(width 0.1524)
				(type default)
			)
			(layer "F.SilkS")
		)
		(fp_line
			(start -0.7874 0.4064)
			(end -0.7874 -0.4064)
			(stroke
				(width 0.1524)
				(type default)
			)
			(layer "F.SilkS")
		)
		(fp_line
			(start 0.7874 -0.4064)
			(end 0.7874 0.4064)
			(stroke
				(width 0.1524)
				(type default)
			)
			(layer "F.SilkS")
		)
		(fp_line
			(start 0.7874 0.4064)
			(end -0.7874 0.4064)
			(stroke
				(width 0.1524)
				(type default)
			)
			(layer "F.SilkS")
		)
		(fp_line
			(start -0.67945 -0.305054)
			(end -0.12065 -0.305054)
			(stroke
				(width 0.1)
				(type default)
			)
			(layer "F.Fab")
		)
		(fp_line
			(start -0.67945 0.3048)
			(end -0.67945 -0.305054)
			(stroke
				(width 0.1)
				(type default)
			)
			(layer "F.Fab")
		)
		(fp_line
			(start -0.12065 -0.305054)
			(end -0.12065 -0.2794)
			(stroke
				(width 0.1)
				(type default)
			)
			(layer "F.Fab")
		)
		(fp_line
			(start -0.12065 -0.2794)
			(end 0.12065 -0.2794)
			(stroke
				(width 0.1)
				(type default)
			)
			(layer "F.Fab")
		)
		(fp_line
			(start -0.12065 0.2794)
			(end -0.12065 0.3048)
			(stroke
				(width 0.1)
				(type default)
			)
			(layer "F.Fab")
		)
		(fp_line
			(start -0.12065 0.3048)
			(end -0.67945 0.3048)
			(stroke
				(width 0.1)
				(type default)
			)
			(layer "F.Fab")
		)
		(fp_line
			(start 0.120396 0.2794)
			(end -0.12065 0.2794)
			(stroke
				(width 0.1)
				(type default)
			)
			(layer "F.Fab")
		)
		(fp_line
			(start 0.120396 0.3048)
			(end 0.120396 0.2794)
			(stroke
				(width 0.1)
				(type default)
			)
			(layer "F.Fab")
		)
		(fp_line
			(start 0.12065 -0.3048)
			(end 0.67945 -0.3048)
			(stroke
				(width 0.1)
				(type default)
			)
			(layer "F.Fab")
		)
		(fp_line
			(start 0.12065 -0.2794)
			(end 0.12065 -0.3048)
			(stroke
				(width 0.1)
				(type default)
			)
			(layer "F.Fab")
		)
		(fp_line
			(start 0.67945 -0.3048)
			(end 0.67945 0.3048)
			(stroke
				(width 0.1)
				(type default)
			)
			(layer "F.Fab")
		)
		(fp_line
			(start 0.67945 0.3048)
			(end 0.120396 0.3048)
			(stroke
				(width 0.1)
				(type default)
			)
			(layer "F.Fab")
		)
		(pad "1" smd circle
			(at -0.40005 0)
			(size 0 0)
			(layers "F.Cu" "F.Mask" "F.Paste")
			(net "P3V3_AUX")
		)
		(pad "2" smd circle
			(at 0.40005 0)
			(size 0 0)
			(layers "F.Cu" "F.Mask" "F.Paste")
			(net "PECI_MUX_SEL_R")
		)
	)
)
